(kicad_pcb
	(version 20260206)
	(generator "pcbnew")
	(generator_version "10.0")
	(general
		(thickness 1.6)
		(legacy_teardrops no)
	)
	(paper "A4")
	(title_block
		(title "04192023_DAF0TMB3IC0_F0TG_MB_C_brd_V02_OCP.brd")
		(comment 1 "Grand Teton / footprints 2964-2969 of 8354")
	)
	(layers
		(0 "F.Cu" signal "TOP")
		(4 "In1.Cu" signal "GND")
		(6 "In2.Cu" signal "IN1")
		(8 "In3.Cu" signal "GND1")
		(10 "In4.Cu" signal "IN2")
		(12 "In5.Cu" signal "GND2")
		(14 "In6.Cu" signal "IN3")
		(16 "In7.Cu" signal "GND3")
		(18 "In8.Cu" signal "VCC")
		(20 "In9.Cu" signal "VCC1")
		(22 "In10.Cu" signal "GND4")
		(24 "In11.Cu" signal "IN4")
		(26 "In12.Cu" signal "GND5")
		(28 "In13.Cu" signal "IN5")
		(30 "In14.Cu" signal "GND6")
		(32 "In15.Cu" signal "IN6")
		(34 "In16.Cu" signal "GND7")
		(2 "B.Cu" signal "BOTTOM")
		(9 "F.Adhes" user "F.Adhesive")
		(11 "B.Adhes" user "B.Adhesive")
		(13 "F.Paste" user "Package Geometry/Pastemask Top")
		(15 "B.Paste" user "Package Geometry/Pastemask Bottom")
		(5 "F.SilkS" user "Ref Des/Silkscreen Top")
		(7 "B.SilkS" user "Ref Des/Silkscreen Bottom")
		(1 "F.Mask" user "Board Geometry/Soldermask Top")
		(3 "B.Mask" user "Board Geometry/Soldermask Bottom")
		(17 "Dwgs.User" user "User.Drawings")
		(19 "Cmts.User" user "User.Comments")
		(21 "Eco1.User" user "User.Eco1")
		(23 "Eco2.User" user "User.Eco2")
		(25 "Edge.Cuts" user "Board Geometry/Outline")
		(27 "Margin" user)
		(31 "F.CrtYd" user "Package Geometry/Place Bound Top")
		(29 "B.CrtYd" user "Package Geometry/Place Bound Bottom")
		(35 "F.Fab" user "Ref Des/Assembly Top")
		(33 "B.Fab" user "Ref Des/Assembly Bottom")
	)
	(footprint ""
		(layer "F.Cu")
		(at 105.84561 -63.54191)
		(property "Reference" "R6220"
			(at 0 0 0)
			(layer "F.SilkS")
			(hide yes)
			(effects
				(font
					(size 1.27 1.27)
				)
			)
		)
		(property "Value" ""
			(at 0 0 0)
			(layer "F.Fab")
			(effects
				(font
					(size 1.27 1.27)
				)
			)
		)
		(duplicate_pad_numbers_are_jumpers no)
		(fp_line
			(start -0.7874 -0.4064)
			(end 0.7874 -0.4064)
			(stroke
				(width 0.1524)
				(type default)
			)
			(layer "F.SilkS")
		)
		(fp_line
			(start -0.7874 0.4064)
			(end -0.7874 -0.4064)
			(stroke
				(width 0.1524)
				(type default)
			)
			(layer "F.SilkS")
		)
		(fp_line
			(start 0.7874 -0.4064)
			(end 0.7874 0.4064)
			(stroke
				(width 0.1524)
				(type default)
			)
			(layer "F.SilkS")
		)
		(fp_line
			(start 0.7874 0.4064)
			(end -0.7874 0.4064)
			(stroke
				(width 0.1524)
				(type default)
			)
			(layer "F.SilkS")
		)
		(fp_line
			(start -0.67945 -0.305054)
			(end -0.12065 -0.305054)
			(stroke
				(width 0.1)
				(type default)
			)
			(layer "F.Fab")
		)
		(fp_line
			(start -0.67945 0.3048)
			(end -0.67945 -0.305054)
			(stroke
				(width 0.1)
				(type default)
			)
			(layer "F.Fab")
		)
		(fp_line
			(start -0.12065 -0.305054)
			(end -0.12065 -0.2794)
			(stroke
				(width 0.1)
				(type default)
			)
			(layer "F.Fab")
		)
		(fp_line
			(start -0.12065 -0.2794)
			(end 0.12065 -0.2794)
			(stroke
				(width 0.1)
				(type default)
			)
			(layer "F.Fab")
		)
		(fp_line
			(start -0.12065 0.2794)
			(end -0.12065 0.3048)
			(stroke
				(width 0.1)
				(type default)
			)
			(layer "F.Fab")
		)
		(fp_line
			(start -0.12065 0.3048)
			(end -0.67945 0.3048)
			(stroke
				(width 0.1)
				(type default)
			)
			(layer "F.Fab")
		)
		(fp_line
			(start 0.120396 0.2794)
			(end -0.12065 0.2794)
			(stroke
				(width 0.1)
				(type default)
			)
			(layer "F.Fab")
		)
		(fp_line
			(start 0.120396 0.3048)
			(end 0.120396 0.2794)
			(stroke
				(width 0.1)
				(type default)
			)
			(layer "F.Fab")
		)
		(fp_line
			(start 0.12065 -0.3048)
			(end 0.67945 -0.3048)
			(stroke
				(width 0.1)
				(type default)
			)
			(layer "F.Fab")
		)
		(fp_line
			(start 0.12065 -0.2794)
			(end 0.12065 -0.3048)
			(stroke
				(width 0.1)
				(type default)
			)
			(layer "F.Fab")
		)
		(fp_line
			(start 0.67945 -0.3048)
			(end 0.67945 0.3048)
			(stroke
				(width 0.1)
				(type default)
			)
			(layer "F.Fab")
		)
		(fp_line
			(start 0.67945 0.3048)
			(end 0.120396 0.3048)
			(stroke
				(width 0.1)
				(type default)
			)
			(layer "F.Fab")
		)
		(pad "1" smd circle
			(at -0.40005 0)
			(size 0 0)
			(layers "F.Cu" "F.Mask" "F.Paste")
			(net "P3V3_AUX")
		)
		(pad "2" smd circle
			(at 0.40005 0)
			(size 0 0)
			(layers "F.Cu" "F.Mask" "F.Paste")
			(net "USB_CPU0_ADD_A2")
		)
	)
	(footprint ""
		(layer "F.Cu")
		(at 205.203044 -109.561376)
		(property "Reference" "R6078"
			(at 0 0 0)
			(layer "F.SilkS")
			(hide yes)
			(effects
				(font
					(size 1.27 1.27)
				)
			)
		)
		(property "Value" ""
			(at 0 0 0)
			(layer "F.Fab")
			(effects
				(font
					(size 1.27 1.27)
				)
			)
		)
		(duplicate_pad_numbers_are_jumpers no)
		(fp_line
			(start -0.7874 -0.4064)
			(end 0.7874 -0.4064)
			(stroke
				(width 0.1524)
				(type default)
			)
			(layer "F.SilkS")
		)
		(fp_line
			(start -0.7874 0.4064)
			(end -0.7874 -0.4064)
			(stroke
				(width 0.1524)
				(type default)
			)
			(layer "F.SilkS")
		)
		(fp_line
			(start 0.7874 -0.4064)
			(end 0.7874 0.4064)
			(stroke
				(width 0.1524)
				(type default)
			)
			(layer "F.SilkS")
		)
		(fp_line
			(start 0.7874 0.4064)
			(end -0.7874 0.4064)
			(stroke
				(width 0.1524)
				(type default)
			)
			(layer "F.SilkS")
		)
		(fp_line
			(start -0.67945 -0.305054)
			(end -0.12065 -0.305054)
			(stroke
				(width 0.1)
				(type default)
			)
			(layer "F.Fab")
		)
		(fp_line
			(start -0.67945 0.3048)
			(end -0.67945 -0.305054)
			(stroke
				(width 0.1)
				(type default)
			)
			(layer "F.Fab")
		)
		(fp_line
			(start -0.12065 -0.305054)
			(end -0.12065 -0.2794)
			(stroke
				(width 0.1)
				(type default)
			)
			(layer "F.Fab")
		)
		(fp_line
			(start -0.12065 -0.2794)
			(end 0.12065 -0.2794)
			(stroke
				(width 0.1)
				(type default)
			)
			(layer "F.Fab")
		)
		(fp_line
			(start -0.12065 0.2794)
			(end -0.12065 0.3048)
			(stroke
				(width 0.1)
				(type default)
			)
			(layer "F.Fab")
		)
		(fp_line
			(start -0.12065 0.3048)
			(end -0.67945 0.3048)
			(stroke
				(width 0.1)
				(type default)
			)
			(layer "F.Fab")
		)
		(fp_line
			(start 0.120396 0.2794)
			(end -0.12065 0.2794)
			(stroke
				(width 0.1)
				(type default)
			)
			(layer "F.Fab")
		)
		(fp_line
			(start 0.120396 0.3048)
			(end 0.120396 0.2794)
			(stroke
				(width 0.1)
				(type default)
			)
			(layer "F.Fab")
		)
		(fp_line
			(start 0.12065 -0.3048)
			(end 0.67945 -0.3048)
			(stroke
				(width 0.1)
				(type default)
			)
			(layer "F.Fab")
		)
		(fp_line
			(start 0.12065 -0.2794)
			(end 0.12065 -0.3048)
			(stroke
				(width 0.1)
				(type default)
			)
			(layer "F.Fab")
		)
		(fp_line
			(start 0.67945 -0.3048)
			(end 0.67945 0.3048)
			(stroke
				(width 0.1)
				(type default)
			)
			(layer "F.Fab")
		)
		(fp_line
			(start 0.67945 0.3048)
			(end 0.120396 0.3048)
			(stroke
				(width 0.1)
				(type default)
			)
			(layer "F.Fab")
		)
		(pad "1" smd circle
			(at -0.40005 0)
			(size 0 0)
			(layers "F.Cu" "F.Mask" "F.Paste")
			(net "PWRGD_P3V3_AUX")
		)
		(pad "2" smd circle
			(at 0.40005 0)
			(size 0 0)
			(layers "F.Cu" "F.Mask" "F.Paste")
			(net "PWRGD_P3V3_AUX_PDB")
		)
	)
	(footprint ""
		(layer "F.Cu")
		(at 211.709 -119.634)
		(property "Reference" "R9023"
			(at 0 0 0)
			(layer "F.SilkS")
			(hide yes)
			(effects
				(font
					(size 1.27 1.27)
				)
			)
		)
		(property "Value" ""
			(at 0 0 0)
			(layer "F.Fab")
			(effects
				(font
					(size 1.27 1.27)
				)
			)
		)
		(duplicate_pad_numbers_are_jumpers no)
		(fp_line
			(start -0.7874 -0.4064)
			(end 0.7874 -0.4064)
			(stroke
				(width 0.1524)
				(type default)
			)
			(layer "F.SilkS")
		)
		(fp_line
			(start -0.7874 0.4064)
			(end -0.7874 -0.4064)
			(stroke
				(width 0.1524)
				(type default)
			)
			(layer "F.SilkS")
		)
		(fp_line
			(start 0.7874 -0.4064)
			(end 0.7874 0.4064)
			(stroke
				(width 0.1524)
				(type default)
			)
			(layer "F.SilkS")
		)
		(fp_line
			(start 0.7874 0.4064)
			(end -0.7874 0.4064)
			(stroke
				(width 0.1524)
				(type default)
			)
			(layer "F.SilkS")
		)
		(fp_line
			(start -0.67945 -0.305054)
			(end -0.12065 -0.305054)
			(stroke
				(width 0.1)
				(type default)
			)
			(layer "F.Fab")
		)
		(fp_line
			(start -0.67945 0.3048)
			(end -0.67945 -0.305054)
			(stroke
				(width 0.1)
				(type default)
			)
			(layer "F.Fab")
		)
		(fp_line
			(start -0.12065 -0.305054)
			(end -0.12065 -0.2794)
			(stroke
				(width 0.1)
				(type default)
			)
			(layer "F.Fab")
		)
		(fp_line
			(start -0.12065 -0.2794)
			(end 0.12065 -0.2794)
			(stroke
				(width 0.1)
				(type default)
			)
			(layer "F.Fab")
		)
		(fp_line
			(start -0.12065 0.2794)
			(end -0.12065 0.3048)
			(stroke
				(width 0.1)
				(type default)
			)
			(layer "F.Fab")
		)
		(fp_line
			(start -0.12065 0.3048)
			(end -0.67945 0.3048)
			(stroke
				(width 0.1)
				(type default)
			)
			(layer "F.Fab")
		)
		(fp_line
			(start 0.120396 0.2794)
			(end -0.12065 0.2794)
			(stroke
				(width 0.1)
				(type default)
			)
			(layer "F.Fab")
		)
		(fp_line
			(start 0.120396 0.3048)
			(end 0.120396 0.2794)
			(stroke
				(width 0.1)
				(type default)
			)
			(layer "F.Fab")
		)
		(fp_line
			(start 0.12065 -0.3048)
			(end 0.67945 -0.3048)
			(stroke
				(width 0.1)
				(type default)
			)
			(layer "F.Fab")
		)
		(fp_line
			(start 0.12065 -0.2794)
			(end 0.12065 -0.3048)
			(stroke
				(width 0.1)
				(type default)
			)
			(layer "F.Fab")
		)
		(fp_line
			(start 0.67945 -0.3048)
			(end 0.67945 0.3048)
			(stroke
				(width 0.1)
				(type default)
			)
			(layer "F.Fab")
		)
		(fp_line
			(start 0.67945 0.3048)
			(end 0.120396 0.3048)
			(stroke
				(width 0.1)
				(type default)
			)
			(layer "F.Fab")
		)
		(pad "1" smd circle
			(at -0.40005 0)
			(size 0 0)
			(layers "F.Cu" "F.Mask" "F.Paste")
			(net "RST_PERST_OCP_SFF_N")
		)
		(pad "2" smd circle
			(at 0.40005 0)
			(size 0 0)
			(layers "F.Cu" "F.Mask" "F.Paste")
			(net "RST_PERST_OCP_SFF_R_N")
		)
	)
	(footprint ""
		(layer "F.Cu")
		(at 295.642792 -346.866464 -90)
		(property "Reference" "PC151_2"
			(at 0 0 270)
			(layer "F.SilkS")
			(hide yes)
			(effects
				(font
					(size 1.27 1.27)
				)
			)
		)
		(property "Value" ""
			(at 0 0 270)
			(layer "F.Fab")
			(effects
				(font
					(size 1.27 1.27)
				)
			)
		)
		(duplicate_pad_numbers_are_jumpers no)
		(fp_line
			(start -0.7874 0.4064)
			(end -0.7874 -0.4064)
			(stroke
				(width 0.1524)
				(type default)
			)
			(layer "F.SilkS")
		)
		(fp_line
			(start 0.7874 0.4064)
			(end -0.7874 0.4064)
			(stroke
				(width 0.1524)
				(type default)
			)
			(layer "F.SilkS")
		)
		(fp_line
			(start -0.7874 -0.4064)
			(end 0.7874 -0.4064)
			(stroke
				(width 0.1524)
				(type default)
			)
			(layer "F.SilkS")
		)
		(fp_line
			(start 0.7874 -0.4064)
			(end 0.7874 0.4064)
			(stroke
				(width 0.1524)
				(type default)
			)
			(layer "F.SilkS")
		)
		(fp_line
			(start -0.67945 0.3048)
			(end -0.67945 -0.305054)
			(stroke
				(width 0.1)
				(type default)
			)
			(layer "F.Fab")
		)
		(fp_line
			(start -0.12065 0.3048)
			(end -0.67945 0.3048)
			(stroke
				(width 0.1)
				(type default)
			)
			(layer "F.Fab")
		)
		(fp_line
			(start 0.120396 0.3048)
			(end 0.120396 0.2794)
			(stroke
				(width 0.1)
				(type default)
			)
			(layer "F.Fab")
		)
		(fp_line
			(start 0.67945 0.3048)
			(end 0.120396 0.3048)
			(stroke
				(width 0.1)
				(type default)
			)
			(layer "F.Fab")
		)
		(fp_line
			(start -0.12065 0.2794)
			(end -0.12065 0.3048)
			(stroke
				(width 0.1)
				(type default)
			)
			(layer "F.Fab")
		)
		(fp_line
			(start 0.120396 0.2794)
			(end -0.12065 0.2794)
			(stroke
				(width 0.1)
				(type default)
			)
			(layer "F.Fab")
		)
		(fp_line
			(start -0.12065 -0.2794)
			(end 0.12065 -0.2794)
			(stroke
				(width 0.1)
				(type default)
			)
			(layer "F.Fab")
		)
		(fp_line
			(start 0.12065 -0.2794)
			(end 0.12065 -0.3048)
			(stroke
				(width 0.1)
				(type default)
			)
			(layer "F.Fab")
		)
		(fp_line
			(start 0.12065 -0.3048)
			(end 0.67945 -0.3048)
			(stroke
				(width 0.1)
				(type default)
			)
			(layer "F.Fab")
		)
		(fp_line
			(start 0.67945 -0.3048)
			(end 0.67945 0.3048)
			(stroke
				(width 0.1)
				(type default)
			)
			(layer "F.Fab")
		)
		(fp_line
			(start -0.67945 -0.305054)
			(end -0.12065 -0.305054)
			(stroke
				(width 0.1)
				(type default)
			)
			(layer "F.Fab")
		)
		(fp_line
			(start -0.12065 -0.305054)
			(end -0.12065 -0.2794)
			(stroke
				(width 0.1)
				(type default)
			)
			(layer "F.Fab")
		)
		(pad "1" smd circle
			(at -0.40005 0 270)
			(size 0 0)
			(layers "F.Cu" "F.Mask" "F.Paste")
			(net "SW_P12V_AUX_PVDDIO_P0_FLT")
		)
		(pad "2" smd circle
			(at 0.40005 0 270)
			(size 0 0)
			(layers "F.Cu" "F.Mask" "F.Paste")
			(net "GND")
		)
	)
	(footprint ""
		(layer "F.Cu")
		(at 246.245888 -293.13505 -90)
		(property "Reference" "PC6506"
			(at 0 0 270)
			(layer "F.SilkS")
			(hide yes)
			(effects
				(font
					(size 1.27 1.27)
				)
			)
		)
		(property "Value" ""
			(at 0 0 270)
			(layer "F.Fab")
			(effects
				(font
					(size 1.27 1.27)
				)
			)
		)
		(duplicate_pad_numbers_are_jumpers no)
		(fp_line
			(start -0.7874 0.4064)
			(end -0.7874 -0.4064)
			(stroke
				(width 0.1524)
				(type default)
			)
			(layer "F.SilkS")
		)
		(fp_line
			(start 0.7874 0.4064)
			(end -0.7874 0.4064)
			(stroke
				(width 0.1524)
				(type default)
			)
			(layer "F.SilkS")
		)
		(fp_line
			(start -0.7874 -0.4064)
			(end 0.7874 -0.4064)
			(stroke
				(width 0.1524)
				(type default)
			)
			(layer "F.SilkS")
		)
		(fp_line
			(start 0.7874 -0.4064)
			(end 0.7874 0.4064)
			(stroke
				(width 0.1524)
				(type default)
			)
			(layer "F.SilkS")
		)
		(fp_line
			(start -0.67945 0.3048)
			(end -0.67945 -0.305054)
			(stroke
				(width 0.1)
				(type default)
			)
			(layer "F.Fab")
		)
		(fp_line
			(start -0.12065 0.3048)
			(end -0.67945 0.3048)
			(stroke
				(width 0.1)
				(type default)
			)
			(layer "F.Fab")
		)
		(fp_line
			(start 0.120396 0.3048)
			(end 0.120396 0.2794)
			(stroke
				(width 0.1)
				(type default)
			)
			(layer "F.Fab")
		)
		(fp_line
			(start 0.67945 0.3048)
			(end 0.120396 0.3048)
			(stroke
				(width 0.1)
				(type default)
			)
			(layer "F.Fab")
		)
		(fp_line
			(start -0.12065 0.2794)
			(end -0.12065 0.3048)
			(stroke
				(width 0.1)
				(type default)
			)
			(layer "F.Fab")
		)
		(fp_line
			(start 0.120396 0.2794)
			(end -0.12065 0.2794)
			(stroke
				(width 0.1)
				(type default)
			)
			(layer "F.Fab")
		)
		(fp_line
			(start -0.12065 -0.2794)
			(end 0.12065 -0.2794)
			(stroke
				(width 0.1)
				(type default)
			)
			(layer "F.Fab")
		)
		(fp_line
			(start 0.12065 -0.2794)
			(end 0.12065 -0.3048)
			(stroke
				(width 0.1)
				(type default)
			)
			(layer "F.Fab")
		)
		(fp_line
			(start 0.12065 -0.3048)
			(end 0.67945 -0.3048)
			(stroke
				(width 0.1)
				(type default)
			)
			(layer "F.Fab")
		)
		(fp_line
			(start 0.67945 -0.3048)
			(end 0.67945 0.3048)
			(stroke
				(width 0.1)
				(type default)
			)
			(layer "F.Fab")
		)
		(fp_line
			(start -0.67945 -0.305054)
			(end -0.12065 -0.305054)
			(stroke
				(width 0.1)
				(type default)
			)
			(layer "F.Fab")
		)
		(fp_line
			(start -0.12065 -0.305054)
			(end -0.12065 -0.2794)
			(stroke
				(width 0.1)
				(type default)
			)
			(layer "F.Fab")
		)
		(pad "1" smd circle
			(at -0.40005 0 270)
			(size 0 0)
			(layers "F.Cu" "F.Mask" "F.Paste")
			(net "P1V8_RETIMER_CPU0_VCC")
		)
		(pad "2" smd circle
			(at 0.40005 0 270)
			(size 0 0)
			(layers "F.Cu" "F.Mask" "F.Paste")
			(net "GND")
		)
	)
	(footprint ""
		(layer "F.Cu")
		(at 339.70722 -337.689698 90)
		(property "Reference" "PC131"
			(at 0 0 90)
			(layer "F.SilkS")
			(hide yes)
			(effects
				(font
					(size 1.27 1.27)
				)
			)
		)
		(property "Value" ""
			(at 0 0 90)
			(layer "F.Fab")
			(effects
				(font
					(size 1.27 1.27)
				)
			)
		)
		(duplicate_pad_numbers_are_jumpers no)
		(fp_line
			(start 0.7874 -0.4064)
			(end 0.7874 0.4064)
			(stroke
				(width 0.1524)
				(type default)
			)
			(layer "F.SilkS")
		)
		(fp_line
			(start -0.7874 -0.4064)
			(end 0.7874 -0.4064)
			(stroke
				(width 0.1524)
				(type default)
			)
			(layer "F.SilkS")
		)
		(fp_line
			(start 0.7874 0.4064)
			(end 0.435102 0.4064)
			(stroke
				(width 0.1524)
				(type default)
			)
			(layer "F.SilkS")
		)
		(fp_line
			(start -0.174498 0.4064)
			(end -0.7874 0.4064)
			(stroke
				(width 0.1524)
				(type default)
			)
			(layer "F.SilkS")
		)
		(fp_line
			(start -0.7874 0.4064)
			(end -0.7874 -0.4064)
			(stroke
				(width 0.1524)
				(type default)
			)
			(layer "F.SilkS")
		)
		(fp_line
			(start -0.12065 -0.305054)
			(end -0.12065 -0.2794)
			(stroke
				(width 0.1)
				(type default)
			)
			(layer "F.Fab")
		)
		(fp_line
			(start -0.67945 -0.305054)
			(end -0.12065 -0.305054)
			(stroke
				(width 0.1)
				(type default)
			)
			(layer "F.Fab")
		)
		(fp_line
			(start 0.67945 -0.3048)
			(end 0.67945 0.3048)
			(stroke
				(width 0.1)
				(type default)
			)
			(layer "F.Fab")
		)
		(fp_line
			(start 0.12065 -0.3048)
			(end 0.67945 -0.3048)
			(stroke
				(width 0.1)
				(type default)
			)
			(layer "F.Fab")
		)
		(fp_line
			(start 0.12065 -0.2794)
			(end 0.12065 -0.3048)
			(stroke
				(width 0.1)
				(type default)
			)
			(layer "F.Fab")
		)
		(fp_line
			(start -0.12065 -0.2794)
			(end 0.12065 -0.2794)
			(stroke
				(width 0.1)
				(type default)
			)
			(layer "F.Fab")
		)
		(fp_line
			(start 0.120396 0.2794)
			(end -0.12065 0.2794)
			(stroke
				(width 0.1)
				(type default)
			)
			(layer "F.Fab")
		)
		(fp_line
			(start -0.12065 0.2794)
			(end -0.12065 0.3048)
			(stroke
				(width 0.1)
				(type default)
			)
			(layer "F.Fab")
		)
		(fp_line
			(start 0.67945 0.3048)
			(end 0.120396 0.3048)
			(stroke
				(width 0.1)
				(type default)
			)
			(layer "F.Fab")
		)
		(fp_line
			(start 0.120396 0.3048)
			(end 0.120396 0.2794)
			(stroke
				(width 0.1)
				(type default)
			)
			(layer "F.Fab")
		)
		(fp_line
			(start -0.12065 0.3048)
			(end -0.67945 0.3048)
			(stroke
				(width 0.1)
				(type default)
			)
			(layer "F.Fab")
		)
		(fp_line
			(start -0.67945 0.3048)
			(end -0.67945 -0.305054)
			(stroke
				(width 0.1)
				(type default)
			)
			(layer "F.Fab")
		)
		(pad "1" smd circle
			(at -0.40005 0 90)
			(size 0 0)
			(layers "F.Cu" "F.Mask" "F.Paste")
			(net "PVDDCR_CPU1_P0_VCC5")
		)
		(pad "2" smd circle
			(at 0.40005 0 90)
			(size 0 0)
			(layers "F.Cu" "F.Mask" "F.Paste")
			(net "GND")
		)
	)
)
